FILE_TYPE = CONNECTIVITY;
{Allegro Design Entry HDL 16.6-p007 (v16-6-112F) 10/10/2012}
"PAGE_NUMBER" = 83;
0"NC";
1"M_K_DQS_DN<17:0>";
2"M_K_DQS_DP<17:0>";
3"M_K_DQ<63:0>";
4"M_K_MA<17:0>";
5"M_K_CLK_DP<3:0>";
6"M_K_CLK_DN<3:0>";
7"M_K_BG<1:0>";
8"M_K_BA<1:0>";
9"M_K_CS_N<7:0>";
10"M_K_ECC<7:0>";
11"M_K_CKE<3:0>";
12"M_K_ODT<3:0>";
13"PVDDQ_KLM\g";
14"GND\g";
15"PVTT_KLM\g";
16"GND\g";
17"GND\g";
18"PVPP_KLM\g";
19"PVPP_KLM\g";
20"P12V_NVDIMM_KLM\g";
21"GND\g";
22"M_K_MA<14>";
23"M_K_MA<13>";
24"M_K_MA<12>";
25"M_K_DQ<59>";
26"M_K_DQ<52>";
27"M_K_DQS_DN<5>";
28"M_K_ALERT_N";
29"M_K_VREF";
30"TP_CH_K_DIMM_K0_RFU_1";
31"TP_CH_K_DIMM_K0_RFU_0";
32"TP_CH_K_DIMM_K0_RFU_2";
33"SMB_DDR_KLM_VPP_SDA";
34"SMB_DDR_KLM_VPP_SCL";
35"FM_ADR_COMPLETE_KLM_N";
36"FM_DIMM_EVENT_COD_N";
37"M_KLM_RST_N";
38"M_K_PAR";
39"M_K_C<2>";
40"M_K_CS_N<0>";
41"M_K_CKE<0>";
42"M_K_ODT<1>";
43"M_K_ODT<0>";
44"M_K_ECC<6>";
45"M_K_BA<0>";
46"M_K_BG<1>";
47"M_K_CKE<1>";
48"M_K_ECC<1>";
49"M_K_ECC<0>";
50"M_K_ECC<3>";
51"M_K_ECC<2>";
52"M_K_ECC<5>";
53"M_K_ECC<4>";
54"M_K_ECC<7>";
55"M_K_MA<1>";
56"M_K_MA<0>";
57"M_K_CS_N<1>";
58"M_K_CS_N<2>";
59"M_K_CS_N<3>";
60"M_K_BA<1>";
61"M_K_BG<0>";
62"M_K_CLK_DN<0>";
63"M_K_CLK_DP<0>";
64"M_K_CLK_DN<1>";
65"M_K_CLK_DP<1>";
66"M_K_ACT_N";
67"M_K_DQ<4>";
68"M_K_DQ<5>";
69"M_K_DQ<2>";
70"M_K_DQ<3>";
71"M_K_DQ<1>";
72"M_K_DQ<0>";
73"M_K_DQ<7>";
74"M_K_DQ<16>";
75"M_K_DQ<14>";
76"M_K_DQ<6>";
77"M_K_DQ<9>";
78"M_K_DQ<8>";
79"M_K_DQ<11>";
80"M_K_DQ<10>";
81"M_K_DQ<13>";
82"M_K_DQ<12>";
83"M_K_DQ<15>";
84"M_K_DQ<17>";
85"M_K_DQ<27>";
86"M_K_DQ<26>";
87"M_K_DQ<19>";
88"M_K_DQ<18>";
89"M_K_DQ<21>";
90"M_K_DQ<20>";
91"M_K_DQ<22>";
92"M_K_DQ<25>";
93"M_K_DQ<24>";
94"M_K_DQ<23>";
95"M_K_DQ<37>";
96"M_K_DQ<34>";
97"M_K_DQ<31>";
98"M_K_DQ<30>";
99"M_K_DQ<33>";
100"M_K_DQ<32>";
101"M_K_DQ<35>";
102"M_K_DQ<36>";
103"M_K_DQ<29>";
104"M_K_DQ<28>";
105"M_K_DQ<46>";
106"M_K_DQ<39>";
107"M_K_DQ<38>";
108"M_K_DQ<41>";
109"M_K_DQ<40>";
110"M_K_DQ<43>";
111"M_K_DQ<42>";
112"M_K_DQ<45>";
113"M_K_DQ<44>";
114"M_K_DQ<47>";
115"M_K_MA<16>";
116"M_K_MA<15>";
117"M_K_MA<11>";
118"M_K_MA<10>";
119"M_K_MA<2>";
120"M_K_MA<9>";
121"M_K_MA<8>";
122"M_K_MA<7>";
123"M_K_MA<6>";
124"M_K_MA<5>";
125"M_K_MA<3>";
126"M_K_MA<17>";
127"M_K_MA<4>";
128"M_K_DQ<49>";
129"M_K_DQ<48>";
130"M_K_DQ<53>";
131"M_K_DQ<55>";
132"M_K_DQ<56>";
133"M_K_DQ<54>";
134"M_K_DQ<57>";
135"M_K_DQ<50>";
136"M_K_DQ<51>";
137"M_K_DQ<62>";
138"M_K_DQ<63>";
139"M_K_DQ<60>";
140"M_K_DQ<58>";
141"M_K_DQ<61>";
142"M_K_DQS_DN<6>";
143"M_K_DQS_DP<5>";
144"M_K_DQS_DP<4>";
145"M_K_DQS_DN<4>";
146"M_K_DQS_DP<3>";
147"M_K_DQS_DN<3>";
148"M_K_DQS_DP<2>";
149"M_K_DQS_DN<2>";
150"M_K_DQS_DP<1>";
151"M_K_DQS_DN<1>";
152"M_K_DQS_DP<0>";
153"M_K_DQS_DN<0>";
154"M_K_DQS_DP<9>";
155"M_K_DQS_DN<9>";
156"M_K_DQS_DP<8>";
157"M_K_DQS_DN<8>";
158"M_K_DQS_DP<7>";
159"M_K_DQS_DN<7>";
160"M_K_DQS_DP<6>";
161"M_K_DQS_DP<16>";
162"M_K_DQS_DN<16>";
163"M_K_DQS_DP<15>";
164"M_K_DQS_DN<15>";
165"M_K_DQS_DP<14>";
166"M_K_DQS_DN<14>";
167"M_K_DQS_DP<13>";
168"M_K_DQS_DN<13>";
169"M_K_DQS_DP<12>";
170"M_K_DQS_DN<12>";
171"M_K_DQS_DP<11>";
172"M_K_DQS_DN<11>";
173"M_K_DQS_DP<10>";
174"M_K_DQS_DN<10>";
175"M_K_DQS_DP<17>";
176"M_K_DQS_DN<17>";
%"TAP"
"6","(700,4900)","2","mstr_standard","I10";
;
CDS_LIB"mstr_standard"
BODY_TYPE"PLUMBING"
HDL_TAP"TRUE";
"B \NAC \NWC"2;
"S \NAC"
BN"14"165;
%"TAP"
"6","(-1700,2150)","2","mstr_standard","I100";
;
CDS_LIB"mstr_standard"
BODY_TYPE"PLUMBING"
HDL_TAP"TRUE";
"B \NAC \NWC"3;
"S \NAC"
BN"8"78;
%"TAP"
"6","(-1700,2200)","2","mstr_standard","I101";
;
CDS_LIB"mstr_standard"
BODY_TYPE"PLUMBING"
HDL_TAP"TRUE";
"B \NAC \NWC"3;
"S \NAC"
BN"11"79;
%"TAP"
"6","(-1700,1900)","2","mstr_standard","I102";
;
CDS_LIB"mstr_standard"
BODY_TYPE"PLUMBING"
HDL_TAP"TRUE";
"B \NAC \NWC"3;
"S \NAC"
BN"5"68;
%"TAP"
"6","(-1700,1850)","2","mstr_standard","I103";
;
CDS_LIB"mstr_standard"
BODY_TYPE"PLUMBING"
HDL_TAP"TRUE";
"B \NAC \NWC"3;
"S \NAC"
BN"2"69;
%"TAP"
"6","(-1700,1950)","2","mstr_standard","I104";
;
CDS_LIB"mstr_standard"
BODY_TYPE"PLUMBING"
HDL_TAP"TRUE";
"B \NAC \NWC"3;
"S \NAC"
BN"4"67;
%"TAP"
"6","(-1700,2000)","2","mstr_standard","I105";
;
CDS_LIB"mstr_standard"
BODY_TYPE"PLUMBING"
HDL_TAP"TRUE";
"B \NAC \NWC"3;
"S \NAC"
BN"7"73;
%"TAP"
"6","(-1700,2100)","2","mstr_standard","I106";
;
CDS_LIB"mstr_standard"
BODY_TYPE"PLUMBING"
HDL_TAP"TRUE";
"B \NAC \NWC"3;
"S \NAC"
BN"9"77;
%"TAP"
"6","(-1700,2050)","2","mstr_standard","I107";
;
CDS_LIB"mstr_standard"
BODY_TYPE"PLUMBING"
HDL_TAP"TRUE";
"B \NAC \NWC"3;
"S \NAC"
BN"6"76;
%"TAP"
"6","(-1700,1700)","2","mstr_standard","I108";
;
CDS_LIB"mstr_standard"
BODY_TYPE"PLUMBING"
HDL_TAP"TRUE";
"B \NAC \NWC"3;
"S \NAC"
BN"1"71;
%"TAP"
"6","(-1700,1800)","2","mstr_standard","I109";
;
CDS_LIB"mstr_standard"
BODY_TYPE"PLUMBING"
HDL_TAP"TRUE";
"B \NAC \NWC"3;
"S \NAC"
BN"3"70;
%"TAP"
"6","(700,5000)","2","mstr_standard","I11";
;
CDS_LIB"mstr_standard"
BODY_TYPE"PLUMBING"
HDL_TAP"TRUE";
"B \NAC \NWC"2;
"S \NAC"
BN"15"163;
%"TAP"
"6","(-1700,1750)","2","mstr_standard","I110";
;
CDS_LIB"mstr_standard"
BODY_TYPE"PLUMBING"
HDL_TAP"TRUE";
"B \NAC \NWC"3;
"S \NAC"
BN"0"72;
%"SCONN288_H44441004"
"1","(-2450,3200)","0","mstr_sconn","I111";
;
CDS_SEC"1"
LOCATION"J1B1"
PART_NUMBER"H44441-004"
MATERIAL"SCONN"
PACK_TYPE"PIP"
BOM_COST"MEM"
CDS_LIB"mstr_sconn"
SEC_TYPE"PIP"
SEC"1"
CDS_LOCATION"J1B1"
ROOM"DDR4_CH_K";
"DQ<63>"
$PN"280"137;
"DQ<62>"
$PN"135"138;
"DQ<61>"
$PN"273"139;
"DQ<5>"
$PN"148"67;
"DQ<4>"
$PN"3"68;
"DQ<3>"
$PN"157"69;
"DQ<2>"
$PN"12"70;
"DQ<47>"
$PN"258"105;
"DQ<48>"
$PN"119"128;
"DQ<49>"
$PN"264"129;
"DQ<50>"
$PN"126"136;
"DQ<51>"
$PN"271"135;
"DQ<52>"
$PN"117"130;
"DQ<53>"
$PN"262"26;
"DQ<54>"
$PN"124"131;
"DQ<58>"
$PN"137"25;
"DQ<57>"
$PN"275"132;
"SAVE_N_NC"
$PN"230"35;
"RFU<1>"
$PN"227"30;
"RFU<0>"
$PN"205"31;
"DQ<17>"
$PN"172"74;
"DQ<15>"
$PN"166"75;
"DQ<26>"
$PN"45"85;
"DQ<27>"
$PN"190"86;
"S0_N"
$PN"84"40;
"CKE<0>"
$PN"60"41;
"ODT<1>"
$PN"91"42;
"ODT<0>"
$PN"87"43;
"CB<7>"
$PN"199"44;
"A16_RAS_N"
$PN"82"115;
"A15_CAS_N"
$PN"86"116;
"A14_WE_N"
$PN"228"22;
"A11"
$PN"210"117;
"A10"
$PN"225"118;
"DQ<38>"
$PN"102"106;
"DQ<36>"
$PN"95"95;
"DQ<35>"
$PN"249"96;
"A2"
$PN"216"119;
"ALERT_N"
$PN"208"28;
"ACT_N"
$PN"62"66;
"DQ<0>"
$PN"5"71;
"DQ<1>"
$PN"150"72;
"SA<1>"
$PN"140"16;
"SA<2>"
$PN"238"16;
"VDDSPD"
$PN"284"19;
"SA<0>"
$PN"139"16;
"BA<0>"
$PN"81"45;
"BG<1>"
$PN"207"46;
"BG<0>"
$PN"63"61;
"CK1P"
$PN"218"65;
"VREFCA"
$PN"146"29;
"SDA"
$PN"285"33;
"SCL"
$PN"141"34;
"RFU<2>"
$PN"144"32;
"RESET_N"
$PN"58"37;
"PAR"
$PN"222"38;
"EVENT_N"
$PN"78"36;
"DQ<6>"
$PN"10"73;
"DQ<7>"
$PN"155"76;
"DQ<8>"
$PN"16"77;
"DQ<9>"
$PN"161"78;
"DQ<10>"
$PN"23"79;
"DQ<11>"
$PN"168"80;
"DQ<12>"
$PN"14"81;
"DQ<13>"
$PN"159"82;
"DQ<14>"
$PN"21"83;
"DQ<16>"
$PN"27"84;
"DQ<18>"
$PN"34"87;
"DQ<19>"
$PN"179"88;
"DQ<20>"
$PN"25"89;
"DQ<21>"
$PN"170"90;
"DQ<22>"
$PN"32"94;
"DQ<23>"
$PN"177"91;
"DQ<24>"
$PN"38"92;
"DQ<25>"
$PN"183"93;
"DQ<30>"
$PN"43"97;
"DQ<31>"
$PN"188"98;
"DQ<32>"
$PN"97"99;
"DQ<33>"
$PN"242"100;
"DQ<34>"
$PN"104"101;
"DQ<37>"
$PN"240"102;
"DQ<39>"
$PN"247"107;
"DQ<40>"
$PN"108"108;
"DQ<41>"
$PN"253"109;
"DQ<42>"
$PN"115"110;
"DQ<43>"
$PN"260"111;
"DQ<44>"
$PN"106"112;
"DQ<45>"
$PN"251"113;
"DQ<46>"
$PN"113"114;
"DQ<55>"
$PN"269"133;
"DQ<56>"
$PN"130"134;
"DQ<59>"
$PN"282"140;
"DQ<60>"
$PN"128"141;
"CKE<1>"
$PN"203"47;
"CK0N"
$PN"75"62;
"CB<0>"
$PN"49"48;
"CB<1>"
$PN"194"49;
"CB<2>"
$PN"56"50;
"CB<3>"
$PN"201"51;
"CB<4>"
$PN"47"52;
"CB<5>"
$PN"192"53;
"CB<6>"
$PN"54"54;
"A9"
$PN"66"120;
"A8"
$PN"68"121;
"A7"
$PN"211"122;
"A6"
$PN"69"123;
"A5"
$PN"213"124;
"A4"
$PN"214"127;
"A3"
$PN"71"125;
"A17"
$PN"234"126;
"A13"
$PN"232"23;
"A12"
$PN"65"24;
"A1"
$PN"72"55;
"A0"
$PN"79"56;
"C<2>"
$PN"235"39;
"DQ<28>"
$PN"36"103;
"DQ<29>"
$PN"181"104;
"S1_N"
$PN"89"57;
"S2_N_C<0>"
$PN"93"58;
"S3_N_C<1>"
$PN"237"59;
"CK0P"
$PN"74"63;
"CK1N"
$PN"219"64;
"BA<1>"
$PN"224"60;
%"TAP"
"6","(-3200,4800)","0","mstr_standard","I112";
;
CDS_LIB"mstr_standard"
BODY_TYPE"PLUMBING"
HDL_TAP"TRUE";
"B \NAC \NWC"4;
"S \NAC"
BN"16"115;
%"TAP"
"6","(-3200,4850)","0","mstr_standard","I113";
;
CDS_LIB"mstr_standard"
BODY_TYPE"PLUMBING"
HDL_TAP"TRUE";
"B \NAC \NWC"4;
"S \NAC"
BN"17"126;
%"TAP"
"6","(-3200,4750)","0","mstr_standard","I114";
;
CDS_LIB"mstr_standard"
BODY_TYPE"PLUMBING"
HDL_TAP"TRUE";
"B \NAC \NWC"4;
"S \NAC"
BN"15"116;
%"TAP"
"6","(-3200,4700)","0","mstr_standard","I115";
;
CDS_LIB"mstr_standard"
BODY_TYPE"PLUMBING"
HDL_TAP"TRUE";
"B \NAC \NWC"4;
"S \NAC"
BN"14"22;
%"TAP"
"6","(-3200,4650)","0","mstr_standard","I116";
;
CDS_LIB"mstr_standard"
BODY_TYPE"PLUMBING"
HDL_TAP"TRUE";
"B \NAC \NWC"4;
"S \NAC"
BN"13"23;
%"TAP"
"6","(-3200,4600)","0","mstr_standard","I117";
;
CDS_LIB"mstr_standard"
BODY_TYPE"PLUMBING"
HDL_TAP"TRUE";
"B \NAC \NWC"4;
"S \NAC"
BN"12"24;
%"TAP"
"6","(-3200,4550)","0","mstr_standard","I118";
;
CDS_LIB"mstr_standard"
BODY_TYPE"PLUMBING"
HDL_TAP"TRUE";
"B \NAC \NWC"4;
"S \NAC"
BN"11"117;
%"TAP"
"6","(-3200,4500)","0","mstr_standard","I119";
;
CDS_LIB"mstr_standard"
BODY_TYPE"PLUMBING"
HDL_TAP"TRUE";
"B \NAC \NWC"4;
"S \NAC"
BN"10"118;
%"TAP"
"6","(700,5100)","2","mstr_standard","I12";
;
CDS_LIB"mstr_standard"
BODY_TYPE"PLUMBING"
HDL_TAP"TRUE";
"B \NAC \NWC"2;
"S \NAC"
BN"16"161;
%"TAP"
"6","(-3200,4450)","0","mstr_standard","I120";
;
CDS_LIB"mstr_standard"
BODY_TYPE"PLUMBING"
HDL_TAP"TRUE";
"B \NAC \NWC"4;
"S \NAC"
BN"9"120;
%"TAP"
"6","(-3200,4400)","0","mstr_standard","I121";
;
CDS_LIB"mstr_standard"
BODY_TYPE"PLUMBING"
HDL_TAP"TRUE";
"B \NAC \NWC"4;
"S \NAC"
BN"8"121;
%"TAP"
"6","(-3200,4350)","0","mstr_standard","I122";
;
CDS_LIB"mstr_standard"
BODY_TYPE"PLUMBING"
HDL_TAP"TRUE";
"B \NAC \NWC"4;
"S \NAC"
BN"7"122;
%"TAP"
"6","(-3200,4300)","0","mstr_standard","I123";
;
CDS_LIB"mstr_standard"
BODY_TYPE"PLUMBING"
HDL_TAP"TRUE";
"B \NAC \NWC"4;
"S \NAC"
BN"6"123;
%"TAP"
"6","(-3200,4250)","0","mstr_standard","I124";
;
CDS_LIB"mstr_standard"
BODY_TYPE"PLUMBING"
HDL_TAP"TRUE";
"B \NAC \NWC"4;
"S \NAC"
BN"5"124;
%"TAP"
"6","(-3200,4200)","0","mstr_standard","I125";
;
CDS_LIB"mstr_standard"
BODY_TYPE"PLUMBING"
HDL_TAP"TRUE";
"B \NAC \NWC"4;
"S \NAC"
BN"4"127;
%"TAP"
"6","(-3200,4100)","0","mstr_standard","I126";
;
CDS_LIB"mstr_standard"
BODY_TYPE"PLUMBING"
HDL_TAP"TRUE";
"B \NAC \NWC"4;
"S \NAC"
BN"2"119;
%"TAP"
"6","(-3200,4150)","0","mstr_standard","I127";
;
CDS_LIB"mstr_standard"
BODY_TYPE"PLUMBING"
HDL_TAP"TRUE";
"B \NAC \NWC"4;
"S \NAC"
BN"3"125;
%"TAP"
"6","(-3200,4050)","0","mstr_standard","I128";
;
CDS_LIB"mstr_standard"
BODY_TYPE"PLUMBING"
HDL_TAP"TRUE";
"B \NAC \NWC"4;
"S \NAC"
BN"1"55;
%"TAP"
"6","(-3200,4000)","0","mstr_standard","I129";
;
CDS_LIB"mstr_standard"
BODY_TYPE"PLUMBING"
HDL_TAP"TRUE";
"B \NAC \NWC"4;
"S \NAC"
BN"0"56;
%"TAP"
"6","(700,4600)","2","mstr_standard","I13";
;
CDS_LIB"mstr_standard"
BODY_TYPE"PLUMBING"
HDL_TAP"TRUE";
"B \NAC \NWC"2;
"S \NAC"
BN"11"171;
%"TAP"
"6","(-3200,3900)","0","mstr_standard","I130";
;
CDS_LIB"mstr_standard"
BODY_TYPE"PLUMBING"
HDL_TAP"TRUE";
"B \NAC \NWC"8;
"S \NAC"
BN"1"60;
%"TAP"
"6","(-3200,3850)","0","mstr_standard","I133";
;
CDS_LIB"mstr_standard"
BODY_TYPE"PLUMBING"
HDL_TAP"TRUE";
"B \NAC \NWC"8;
"S \NAC"
BN"0"45;
%"TAP"
"6","(-3200,3800)","0","mstr_standard","I134";
;
CDS_LIB"mstr_standard"
BODY_TYPE"PLUMBING"
HDL_TAP"TRUE";
"B \NAC \NWC"7;
"S \NAC"
BN"1"46;
%"TAP"
"6","(-3200,3750)","0","mstr_standard","I135";
;
CDS_LIB"mstr_standard"
BODY_TYPE"PLUMBING"
HDL_TAP"TRUE";
"B \NAC \NWC"7;
"S \NAC"
BN"0"61;
%"TAP"
"6","(-3200,2800)","0","mstr_standard","I138";
;
CDS_LIB"mstr_standard"
BODY_TYPE"PLUMBING"
HDL_TAP"TRUE";
"B \NAC \NWC"10;
"S \NAC"
BN"6"44;
%"TAP"
"6","(-3200,2750)","0","mstr_standard","I139";
;
CDS_LIB"mstr_standard"
BODY_TYPE"PLUMBING"
HDL_TAP"TRUE";
"B \NAC \NWC"10;
"S \NAC"
BN"7"54;
%"TAP"
"6","(700,4700)","2","mstr_standard","I14";
;
CDS_LIB"mstr_standard"
BODY_TYPE"PLUMBING"
HDL_TAP"TRUE";
"B \NAC \NWC"2;
"S \NAC"
BN"12"169;
%"TAP"
"6","(-3200,2700)","0","mstr_standard","I140";
;
CDS_LIB"mstr_standard"
BODY_TYPE"PLUMBING"
HDL_TAP"TRUE";
"B \NAC \NWC"10;
"S \NAC"
BN"4"53;
%"TAP"
"6","(-3200,2650)","0","mstr_standard","I141";
;
CDS_LIB"mstr_standard"
BODY_TYPE"PLUMBING"
HDL_TAP"TRUE";
"B \NAC \NWC"10;
"S \NAC"
BN"5"52;
%"TAP"
"6","(-3200,2600)","0","mstr_standard","I142";
;
CDS_LIB"mstr_standard"
BODY_TYPE"PLUMBING"
HDL_TAP"TRUE";
"B \NAC \NWC"10;
"S \NAC"
BN"2"51;
%"TAP"
"6","(-3200,2550)","0","mstr_standard","I143";
;
CDS_LIB"mstr_standard"
BODY_TYPE"PLUMBING"
HDL_TAP"TRUE";
"B \NAC \NWC"10;
"S \NAC"
BN"3"50;
%"TAP"
"6","(-3200,2500)","0","mstr_standard","I144";
;
CDS_LIB"mstr_standard"
BODY_TYPE"PLUMBING"
HDL_TAP"TRUE";
"B \NAC \NWC"10;
"S \NAC"
BN"0"49;
%"TAP"
"6","(-3200,2450)","0","mstr_standard","I145";
;
CDS_LIB"mstr_standard"
BODY_TYPE"PLUMBING"
HDL_TAP"TRUE";
"B \NAC \NWC"10;
"S \NAC"
BN"1"48;
%"TAP"
"6","(700,4800)","2","mstr_standard","I15";
;
CDS_LIB"mstr_standard"
BODY_TYPE"PLUMBING"
HDL_TAP"TRUE";
"B \NAC \NWC"2;
"S \NAC"
BN"13"167;
%"TAP"
"6","(-3200,3350)","0","mstr_standard","I152";
;
CDS_LIB"mstr_standard"
BODY_TYPE"PLUMBING"
HDL_TAP"TRUE";
"B \NAC \NWC"9;
"S \NAC"
BN"3"59;
%"TAP"
"6","(-3200,3300)","0","mstr_standard","I153";
;
CDS_LIB"mstr_standard"
BODY_TYPE"PLUMBING"
HDL_TAP"TRUE";
"B \NAC \NWC"9;
"S \NAC"
BN"2"58;
%"TAP"
"6","(-3200,3050)","0","mstr_standard","I154";
;
CDS_LIB"mstr_standard"
BODY_TYPE"PLUMBING"
HDL_TAP"TRUE";
"B \NAC \NWC"11;
"S \NAC"
BN"0"41;
%"TAP"
"6","(-3200,2900)","0","mstr_standard","I155";
;
CDS_LIB"mstr_standard"
BODY_TYPE"PLUMBING"
HDL_TAP"TRUE";
"B \NAC \NWC"12;
"S \NAC"
BN"0"43;
%"TAP"
"6","(-3550,3550)","0","mstr_standard","I156";
;
CDS_LIB"mstr_standard"
BODY_TYPE"PLUMBING"
HDL_TAP"TRUE";
"B \NAC \NWC"5;
"S \NAC"
BN"0"63;
%"TAP"
"6","(-3700,3500)","0","mstr_standard","I159";
;
CDS_LIB"mstr_standard"
BODY_TYPE"PLUMBING"
HDL_TAP"TRUE";
"B \NAC \NWC"6;
"S \NAC"
BN"0"62;
%"PVDDQ_KLM"
"1","(-1300,2625)","0","mstr_symbols","I16";
;
VOLTAGE"1.2V"
BOM_COST"MEM"
CDS_LIB"mstr_symbols"
BODY_TYPE"PLUMBING"
ROOM"DDR4_CH_C"
HDL_POWER"PVDDQ_KLM";
"G\NAC"13;
%"TAP"
"6","(-3200,3250)","0","mstr_standard","I163";
;
CDS_LIB"mstr_standard"
BODY_TYPE"PLUMBING"
HDL_TAP"TRUE";
"B \NAC \NWC"9;
"S \NAC"
BN"1"57;
%"TAP"
"6","(-3200,3200)","0","mstr_standard","I164";
;
CDS_LIB"mstr_standard"
BODY_TYPE"PLUMBING"
HDL_TAP"TRUE";
"B \NAC \NWC"9;
"S \NAC"
BN"0"40;
%"TAP"
"6","(-3200,3100)","0","mstr_standard","I165";
;
CDS_LIB"mstr_standard"
BODY_TYPE"PLUMBING"
HDL_TAP"TRUE";
"B \NAC \NWC"11;
"S \NAC"
BN"1"47;
%"TAP"
"6","(-3200,2950)","0","mstr_standard","I166";
;
CDS_LIB"mstr_standard"
BODY_TYPE"PLUMBING"
HDL_TAP"TRUE";
"B \NAC \NWC"12;
"S \NAC"
BN"1"42;
%"SCONN288_H44441004"
"4","(-150,2100)","0","mstr_sconn","I167";
;
CDS_SEC"4"
LOCATION"J1B1"
PART_NUMBER"H44441-004"
MATERIAL"SCONN"
PACK_TYPE"PIP"
BOM_COST"MEM"
CDS_LIB"mstr_sconn"
SEC_TYPE"PIP"
SEC"4"
CDS_LOCATION"J1B1"
ROOM"DDR4_CH_K";
"VPP<4>"
$PN"142"18;
"VTT<1>"
$PN"77"15;
"VPP<0>"
$PN"287"18;
"VPP<1>"
$PN"286"18;
"VPP<2>"
$PN"288"18;
"VPP<3>"
$PN"143"18;
"VDD<1>"
$PN"233"13;
"VDD<2>"
$PN"231"13;
"VDD<3>"
$PN"229"13;
"VDD<4>"
$PN"226"13;
"VDD<5>"
$PN"223"13;
"VDD<7>"
$PN"217"13;
"VDD<8>"
$PN"215"13;
"VDD<9>"
$PN"212"13;
"VDD<11>"
$PN"206"13;
"VDD<12>"
$PN"204"13;
"VDD<14>"
$PN"90"13;
"VDD<15>"
$PN"88"13;
"VDD<17>"
$PN"83"13;
"VDD<18>"
$PN"80"13;
"VDD<20>"
$PN"73"13;
"VDD<21>"
$PN"70"13;
"VDD<22>"
$PN"67"13;
"VDD<24>"
$PN"61"13;
"12V<0>"
$PN"145"20;
"12V<1>"
$PN"1"20;
"VTT<0>"
$PN"221"15;
"VDD<25>"
$PN"59"13;
"VDD<23>"
$PN"64"13;
"VDD<19>"
$PN"76"13;
"VDD<16>"
$PN"85"13;
"VDD<13>"
$PN"92"13;
"VDD<10>"
$PN"209"13;
"VDD<6>"
$PN"220"13;
"VDD<0>"
$PN"236"13;
%"GND"
"1","(2500,1100)","2","mstr_symbols","I168";
;
VOLTAGE"0"
BOM_COST"MEM"
SIZE"1B"
CDS_LIB"mstr_symbols"
BODY_TYPE"PLUMBING"
ROOM"DDR4_CH_C"
HDL_POWER"GND";
"A\NAC"14;
%"PVTT_KLM"
"1","(-1050,2800)","0","mstr_symbols","I17";
;
VOLTAGE"0.6V"
BOM_COST"MEM"
CDS_LIB"mstr_symbols"
BODY_TYPE"PLUMBING"
ROOM"DDR4_CH_C"
HDL_POWER"PVTT_KLM";
"G\NAC"15;
%"GND"
"1","(-5100,1850)","2","mstr_symbols","I173";
;
VOLTAGE"0"
BOM_COST"MEM"
CDS_LIB"mstr_symbols"
SIZE"1B"
BODY_TYPE"PLUMBING"
ROOM"DDR4_CH_C"
HDL_POWER"GND";
"A\NAC"16;
%"GND"
"1","(-4600,1250)","0","mstr_symbols","I175";
;
VOLTAGE"0"
BOM_COST"MEM"
SIZE"1B"
CDS_LIB"mstr_symbols"
BODY_TYPE"PLUMBING"
ROOM"DDR4_CH_C"
HDL_POWER"GND";
"A\NAC"17;
%"CAP_A"
"1","(-4600,1500)","2","dev_discrete","I176";
;
LOCATION"C1B9"
PART_NUMBER"A36096-045"
VALUE"0.01UF"
TOLERANCE"10%"
PACK_TYPE"0402V"
VOLTAGE"25V"
MATERIAL"X7R"
CDS_LOCATION"C1B9"
BOM_COST"MEM"
CDS_LIB"dev_discrete"
CDS_SEC"1"
$SEC"1"
ROOM"DDR4_CH_K";
"B"
$PN"2"17;
"A"
$PN"1"29;
%"PVPP_KLM"
"1","(-850,3100)","0","mstr_symbols","I177";
;
VOLTAGE"2.5V"
BOM_COST"MEM"
CDS_LIB"mstr_symbols"
BODY_TYPE"PLUMBING"
ROOM"DDR4_CH_C"
HDL_POWER"PVPP_KLM";
"G\NAC"18;
%"PVPP_KLM"
"1","(-5100,2200)","0","mstr_symbols","I178";
;
VOLTAGE"2.5V"
BOM_COST"MEM"
CDS_LIB"mstr_symbols"
BODY_TYPE"PLUMBING"
ROOM"DDR4_CH_C"
HDL_POWER"PVPP_KLM";
"G\NAC"19;
%"TAP"
"6","(-3700,3600)","0","mstr_standard","I183";
;
CDS_LIB"mstr_standard"
BODY_TYPE"PLUMBING"
HDL_TAP"TRUE";
"B \NAC \NWC"6;
"S \NAC"
BN"1"64;
%"TAP"
"6","(-3550,3650)","0","mstr_standard","I184";
;
CDS_LIB"mstr_standard"
BODY_TYPE"PLUMBING"
HDL_TAP"TRUE";
"B \NAC \NWC"5;
"S \NAC"
BN"1"65;
%"P12V_NVDIMM_KLM"
"1","(550,3175)","0","mstr_symbols","I185";
;
VOLTAGE"12.0"
CDS_LIB"mstr_symbols"
BODY_TYPE"PLUMBING"
HDL_POWER"P12V_NVDIMM_KLM";
"G\NAC"20;
%"TAP"
"6","(900,4550)","2","mstr_standard","I19";
;
CDS_LIB"mstr_standard"
BODY_TYPE"PLUMBING"
HDL_TAP"TRUE";
"B \NAC \NWC"1;
"S \NAC"
BN"11"172;
%"TAP"
"6","(900,4450)","2","mstr_standard","I20";
;
CDS_LIB"mstr_standard"
BODY_TYPE"PLUMBING"
HDL_TAP"TRUE";
"B \NAC \NWC"1;
"S \NAC"
BN"10"174;
%"TAP"
"6","(900,4350)","2","mstr_standard","I21";
;
CDS_LIB"mstr_standard"
BODY_TYPE"PLUMBING"
HDL_TAP"TRUE";
"B \NAC \NWC"1;
"S \NAC"
BN"9"155;
%"TAP"
"6","(900,4250)","2","mstr_standard","I22";
;
CDS_LIB"mstr_standard"
BODY_TYPE"PLUMBING"
HDL_TAP"TRUE";
"B \NAC \NWC"1;
"S \NAC"
BN"8"157;
%"TAP"
"6","(900,4150)","2","mstr_standard","I23";
;
CDS_LIB"mstr_standard"
BODY_TYPE"PLUMBING"
HDL_TAP"TRUE";
"B \NAC \NWC"1;
"S \NAC"
BN"7"159;
%"TAP"
"6","(700,4500)","2","mstr_standard","I24";
;
CDS_LIB"mstr_standard"
BODY_TYPE"PLUMBING"
HDL_TAP"TRUE";
"B \NAC \NWC"2;
"S \NAC"
BN"10"173;
%"TAP"
"6","(700,4400)","2","mstr_standard","I25";
;
CDS_LIB"mstr_standard"
BODY_TYPE"PLUMBING"
HDL_TAP"TRUE";
"B \NAC \NWC"2;
"S \NAC"
BN"9"154;
%"TAP"
"6","(700,4100)","2","mstr_standard","I26";
;
CDS_LIB"mstr_standard"
BODY_TYPE"PLUMBING"
HDL_TAP"TRUE";
"B \NAC \NWC"2;
"S \NAC"
BN"6"160;
%"TAP"
"6","(700,4200)","2","mstr_standard","I27";
;
CDS_LIB"mstr_standard"
BODY_TYPE"PLUMBING"
HDL_TAP"TRUE";
"B \NAC \NWC"2;
"S \NAC"
BN"7"158;
%"TAP"
"6","(700,4300)","2","mstr_standard","I28";
;
CDS_LIB"mstr_standard"
BODY_TYPE"PLUMBING"
HDL_TAP"TRUE";
"B \NAC \NWC"2;
"S \NAC"
BN"8"156;
%"TAP"
"6","(900,4050)","2","mstr_standard","I29";
;
CDS_LIB"mstr_standard"
BODY_TYPE"PLUMBING"
HDL_TAP"TRUE";
"B \NAC \NWC"1;
"S \NAC"
BN"6"142;
%"TAP"
"6","(900,5150)","2","mstr_standard","I3";
;
CDS_LIB"mstr_standard"
BODY_TYPE"PLUMBING"
HDL_TAP"TRUE";
"B \NAC \NWC"1;
"S \NAC"
BN"17"176;
%"TAP"
"6","(900,3950)","2","mstr_standard","I30";
;
CDS_LIB"mstr_standard"
BODY_TYPE"PLUMBING"
HDL_TAP"TRUE";
"B \NAC \NWC"1;
"S \NAC"
BN"5"27;
%"TAP"
"6","(900,3850)","2","mstr_standard","I31";
;
CDS_LIB"mstr_standard"
BODY_TYPE"PLUMBING"
HDL_TAP"TRUE";
"B \NAC \NWC"1;
"S \NAC"
BN"4"145;
%"TAP"
"6","(900,3750)","2","mstr_standard","I32";
;
CDS_LIB"mstr_standard"
BODY_TYPE"PLUMBING"
HDL_TAP"TRUE";
"B \NAC \NWC"1;
"S \NAC"
BN"3"147;
%"TAP"
"6","(900,3650)","2","mstr_standard","I33";
;
CDS_LIB"mstr_standard"
BODY_TYPE"PLUMBING"
HDL_TAP"TRUE";
"B \NAC \NWC"1;
"S \NAC"
BN"2"149;
%"TAP"
"6","(700,4000)","2","mstr_standard","I34";
;
CDS_LIB"mstr_standard"
BODY_TYPE"PLUMBING"
HDL_TAP"TRUE";
"B \NAC \NWC"2;
"S \NAC"
BN"5"143;
%"TAP"
"6","(700,3900)","2","mstr_standard","I35";
;
CDS_LIB"mstr_standard"
BODY_TYPE"PLUMBING"
HDL_TAP"TRUE";
"B \NAC \NWC"2;
"S \NAC"
BN"4"144;
%"TAP"
"6","(700,3700)","2","mstr_standard","I36";
;
CDS_LIB"mstr_standard"
BODY_TYPE"PLUMBING"
HDL_TAP"TRUE";
"B \NAC \NWC"2;
"S \NAC"
BN"2"148;
%"TAP"
"6","(700,3600)","2","mstr_standard","I37";
;
CDS_LIB"mstr_standard"
BODY_TYPE"PLUMBING"
HDL_TAP"TRUE";
"B \NAC \NWC"2;
"S \NAC"
BN"1"150;
%"TAP"
"6","(700,3800)","2","mstr_standard","I38";
;
CDS_LIB"mstr_standard"
BODY_TYPE"PLUMBING"
HDL_TAP"TRUE";
"B \NAC \NWC"2;
"S \NAC"
BN"3"146;
%"TAP"
"6","(900,3450)","2","mstr_standard","I39";
;
CDS_LIB"mstr_standard"
BODY_TYPE"PLUMBING"
HDL_TAP"TRUE";
"B \NAC \NWC"1;
"S \NAC"
BN"0"153;
%"TAP"
"6","(700,5200)","2","mstr_standard","I4";
;
CDS_LIB"mstr_standard"
BODY_TYPE"PLUMBING"
HDL_TAP"TRUE";
"B \NAC \NWC"2;
"S \NAC"
BN"17"175;
%"TAP"
"6","(900,3550)","2","mstr_standard","I40";
;
CDS_LIB"mstr_standard"
BODY_TYPE"PLUMBING"
HDL_TAP"TRUE";
"B \NAC \NWC"1;
"S \NAC"
BN"1"151;
%"TAP"
"6","(700,3500)","2","mstr_standard","I41";
;
CDS_LIB"mstr_standard"
BODY_TYPE"PLUMBING"
HDL_TAP"TRUE";
"B \NAC \NWC"2;
"S \NAC"
BN"0"152;
%"SCONN288_H44441004"
"3","(1800,2400)","0","mstr_sconn","I43";
;
CDS_SEC"3"
LOCATION"J1B1"
PART_NUMBER"H44441-004"
MATERIAL"SCONN"
PACK_TYPE"PIP"
BOM_COST"MEM"
CDS_LIB"mstr_sconn"
SEC_TYPE"PIP"
SEC"3"
CDS_LOCATION"J1B1"
ROOM"DDR4_CH_K";
"VSS<93>"
$PN"2"21;
"VSS<92>"
$PN"4"21;
"VSS<91>"
$PN"6"21;
"VSS<90>"
$PN"9"21;
"VSS<89>"
$PN"11"21;
"VSS<88>"
$PN"13"21;
"VSS<0>"
$PN"283"14;
"VSS<1>"
$PN"281"14;
"VSS<2>"
$PN"279"14;
"VSS<3>"
$PN"276"14;
"VSS<4>"
$PN"274"14;
"VSS<5>"
$PN"272"14;
"VSS<6>"
$PN"270"14;
"VSS<7>"
$PN"268"14;
"VSS<8>"
$PN"265"14;
"VSS<9>"
$PN"263"14;
"VSS<10>"
$PN"261"14;
"VSS<11>"
$PN"259"14;
"VSS<12>"
$PN"257"14;
"VSS<13>"
$PN"254"14;
"VSS<14>"
$PN"252"14;
"VSS<15>"
$PN"250"14;
"VSS<16>"
$PN"248"14;
"VSS<17>"
$PN"246"14;
"VSS<18>"
$PN"243"14;
"VSS<19>"
$PN"241"14;
"VSS<20>"
$PN"239"14;
"VSS<21>"
$PN"202"14;
"VSS<22>"
$PN"200"14;
"VSS<23>"
$PN"198"14;
"VSS<24>"
$PN"195"14;
"VSS<25>"
$PN"193"14;
"VSS<26>"
$PN"191"14;
"VSS<27>"
$PN"189"14;
"VSS<28>"
$PN"187"14;
"VSS<29>"
$PN"184"14;
"VSS<30>"
$PN"182"14;
"VSS<31>"
$PN"180"14;
"VSS<32>"
$PN"178"14;
"VSS<33>"
$PN"176"14;
"VSS<34>"
$PN"173"14;
"VSS<35>"
$PN"171"14;
"VSS<36>"
$PN"169"14;
"VSS<37>"
$PN"167"14;
"VSS<38>"
$PN"165"14;
"VSS<39>"
$PN"162"14;
"VSS<40>"
$PN"160"14;
"VSS<41>"
$PN"158"14;
"VSS<42>"
$PN"156"14;
"VSS<43>"
$PN"154"14;
"VSS<44>"
$PN"151"14;
"VSS<47>"
$PN"138"21;
"VSS<48>"
$PN"136"21;
"VSS<49>"
$PN"134"21;
"VSS<50>"
$PN"131"21;
"VSS<51>"
$PN"129"21;
"VSS<52>"
$PN"127"21;
"VSS<53>"
$PN"125"21;
"VSS<54>"
$PN"123"21;
"VSS<55>"
$PN"120"21;
"VSS<56>"
$PN"118"21;
"VSS<57>"
$PN"116"21;
"VSS<58>"
$PN"114"21;
"VSS<59>"
$PN"112"21;
"VSS<60>"
$PN"109"21;
"VSS<61>"
$PN"107"21;
"VSS<62>"
$PN"105"21;
"VSS<63>"
$PN"103"21;
"VSS<64>"
$PN"101"21;
"VSS<65>"
$PN"98"21;
"VSS<66>"
$PN"96"21;
"VSS<67>"
$PN"94"21;
"VSS<68>"
$PN"57"21;
"VSS<69>"
$PN"55"21;
"VSS<70>"
$PN"53"21;
"VSS<71>"
$PN"50"21;
"VSS<72>"
$PN"48"21;
"VSS<73>"
$PN"46"21;
"VSS<74>"
$PN"44"21;
"VSS<75>"
$PN"42"21;
"VSS<76>"
$PN"39"21;
"VSS<77>"
$PN"37"21;
"VSS<78>"
$PN"35"21;
"VSS<79>"
$PN"33"21;
"VSS<80>"
$PN"31"21;
"VSS<81>"
$PN"28"21;
"VSS<82>"
$PN"26"21;
"VSS<83>"
$PN"24"21;
"VSS<84>"
$PN"22"21;
"VSS<85>"
$PN"20"21;
"VSS<86>"
$PN"17"21;
"VSS<87>"
$PN"15"21;
"VSS<45>"
$PN"149"14;
"VSS<46>"
$PN"147"14;
%"GND"
"1","(1100,1100)","2","mstr_symbols","I44";
;
VOLTAGE"0"
BOM_COST"MEM"
SIZE"1B"
CDS_LIB"mstr_symbols"
BODY_TYPE"PLUMBING"
ROOM"DDR4_CH_C"
HDL_POWER"GND";
"A\NAC"21;
%"TAP"
"6","(-1700,4750)","2","mstr_standard","I46";
;
CDS_LIB"mstr_standard"
BODY_TYPE"PLUMBING"
HDL_TAP"TRUE";
"B \NAC \NWC"3;
"S \NAC"
BN"60"139;
%"TAP"
"6","(-1700,4700)","2","mstr_standard","I47";
;
CDS_LIB"mstr_standard"
BODY_TYPE"PLUMBING"
HDL_TAP"TRUE";
"B \NAC \NWC"3;
"S \NAC"
BN"61"141;
%"TAP"
"6","(-1700,4800)","2","mstr_standard","I48";
;
CDS_LIB"mstr_standard"
BODY_TYPE"PLUMBING"
HDL_TAP"TRUE";
"B \NAC \NWC"3;
"S \NAC"
BN"63"138;
%"TAP"
"6","(-1700,4850)","2","mstr_standard","I49";
;
CDS_LIB"mstr_standard"
BODY_TYPE"PLUMBING"
HDL_TAP"TRUE";
"B \NAC \NWC"3;
"S \NAC"
BN"62"137;
%"TAP"
"6","(900,5050)","2","mstr_standard","I5";
;
CDS_LIB"mstr_standard"
BODY_TYPE"PLUMBING"
HDL_TAP"TRUE";
"B \NAC \NWC"1;
"S \NAC"
BN"16"162;
%"TAP"
"6","(-1700,4450)","2","mstr_standard","I50";
;
CDS_LIB"mstr_standard"
BODY_TYPE"PLUMBING"
HDL_TAP"TRUE";
"B \NAC \NWC"3;
"S \NAC"
BN"54"133;
%"TAP"
"6","(-1700,4500)","2","mstr_standard","I51";
;
CDS_LIB"mstr_standard"
BODY_TYPE"PLUMBING"
HDL_TAP"TRUE";
"B \NAC \NWC"3;
"S \NAC"
BN"57"134;
%"TAP"
"6","(-1700,4600)","2","mstr_standard","I52";
;
CDS_LIB"mstr_standard"
BODY_TYPE"PLUMBING"
HDL_TAP"TRUE";
"B \NAC \NWC"3;
"S \NAC"
BN"59"25;
%"TAP"
"6","(-1700,4550)","2","mstr_standard","I53";
;
CDS_LIB"mstr_standard"
BODY_TYPE"PLUMBING"
HDL_TAP"TRUE";
"B \NAC \NWC"3;
"S \NAC"
BN"56"132;
%"TAP"
"6","(-1700,4650)","2","mstr_standard","I54";
;
CDS_LIB"mstr_standard"
BODY_TYPE"PLUMBING"
HDL_TAP"TRUE";
"B \NAC \NWC"3;
"S \NAC"
BN"58"140;
%"TAP"
"6","(-1700,4200)","2","mstr_standard","I55";
;
CDS_LIB"mstr_standard"
BODY_TYPE"PLUMBING"
HDL_TAP"TRUE";
"B \NAC \NWC"3;
"S \NAC"
BN"51"136;
%"TAP"
"6","(-1700,4250)","2","mstr_standard","I56";
;
CDS_LIB"mstr_standard"
BODY_TYPE"PLUMBING"
HDL_TAP"TRUE";
"B \NAC \NWC"3;
"S \NAC"
BN"50"135;
%"TAP"
"6","(-1700,4300)","2","mstr_standard","I57";
;
CDS_LIB"mstr_standard"
BODY_TYPE"PLUMBING"
HDL_TAP"TRUE";
"B \NAC \NWC"3;
"S \NAC"
BN"53"130;
%"TAP"
"6","(-1700,4400)","2","mstr_standard","I58";
;
CDS_LIB"mstr_standard"
BODY_TYPE"PLUMBING"
HDL_TAP"TRUE";
"B \NAC \NWC"3;
"S \NAC"
BN"55"131;
%"TAP"
"6","(-1700,4350)","2","mstr_standard","I59";
;
CDS_LIB"mstr_standard"
BODY_TYPE"PLUMBING"
HDL_TAP"TRUE";
"B \NAC \NWC"3;
"S \NAC"
BN"52"26;
%"TAP"
"6","(900,4950)","2","mstr_standard","I6";
;
CDS_LIB"mstr_standard"
BODY_TYPE"PLUMBING"
HDL_TAP"TRUE";
"B \NAC \NWC"1;
"S \NAC"
BN"15"164;
%"TAP"
"6","(-1700,3900)","2","mstr_standard","I60";
;
CDS_LIB"mstr_standard"
BODY_TYPE"PLUMBING"
HDL_TAP"TRUE";
"B \NAC \NWC"3;
"S \NAC"
BN"45"112;
%"TAP"
"6","(-1700,3950)","2","mstr_standard","I61";
;
CDS_LIB"mstr_standard"
BODY_TYPE"PLUMBING"
HDL_TAP"TRUE";
"B \NAC \NWC"3;
"S \NAC"
BN"44"113;
%"TAP"
"6","(-1700,4000)","2","mstr_standard","I62";
;
CDS_LIB"mstr_standard"
BODY_TYPE"PLUMBING"
HDL_TAP"TRUE";
"B \NAC \NWC"3;
"S \NAC"
BN"47"114;
%"TAP"
"6","(-1700,4100)","2","mstr_standard","I63";
;
CDS_LIB"mstr_standard"
BODY_TYPE"PLUMBING"
HDL_TAP"TRUE";
"B \NAC \NWC"3;
"S \NAC"
BN"49"128;
%"TAP"
"6","(-1700,4050)","2","mstr_standard","I64";
;
CDS_LIB"mstr_standard"
BODY_TYPE"PLUMBING"
HDL_TAP"TRUE";
"B \NAC \NWC"3;
"S \NAC"
BN"46"105;
%"TAP"
"6","(-1700,4150)","2","mstr_standard","I65";
;
CDS_LIB"mstr_standard"
BODY_TYPE"PLUMBING"
HDL_TAP"TRUE";
"B \NAC \NWC"3;
"S \NAC"
BN"48"129;
%"SCONN288_H44441004"
"2","(0,4350)","0","mstr_sconn","I66";
;
CDS_SEC"2"
LOCATION"J1B1"
PART_NUMBER"H44441-004"
MATERIAL"SCONN"
PACK_TYPE"PIP"
BOM_COST"MEM"
CDS_LIB"mstr_sconn"
SEC_TYPE"PIP"
SEC"2"
CDS_LOCATION"J1B1"
ROOM"DDR4_CH_K";
"DQS17P"
$PN"51"175;
"DQS9P"
$PN"7"154;
"DQS9N"
$PN"8"155;
"DQS8P"
$PN"197"156;
"DQS8N"
$PN"196"157;
"DQS7P"
$PN"278"158;
"DQS7N"
$PN"277"159;
"DQS6P"
$PN"267"160;
"DQS6N"
$PN"266"142;
"DQS5P"
$PN"256"143;
"DQS5N"
$PN"255"27;
"DQS4P"
$PN"245"144;
"DQS4N"
$PN"244"145;
"DQS3P"
$PN"186"146;
"DQS3N"
$PN"185"147;
"DQS2P"
$PN"175"148;
"DQS2N"
$PN"174"149;
"DQS1P"
$PN"164"150;
"DQS1N"
$PN"163"151;
"DQS17N"
$PN"52"176;
"DQS16P"
$PN"132"161;
"DQS16N"
$PN"133"162;
"DQS15P"
$PN"121"163;
"DQS15N"
$PN"122"164;
"DQS14P"
$PN"110"165;
"DQS14N"
$PN"111"166;
"DQS13P"
$PN"99"167;
"DQS13N"
$PN"100"168;
"DQS12P"
$PN"40"169;
"DQS12N"
$PN"41"170;
"DQS11P"
$PN"29"171;
"DQS11N"
$PN"30"172;
"DQS10P"
$PN"18"173;
"DQS10N"
$PN"19"174;
"DQS0P"
$PN"153"152;
"DQS0N"
$PN"152"153;
%"TAP"
"6","(-1700,3750)","2","mstr_standard","I67";
;
CDS_LIB"mstr_standard"
BODY_TYPE"PLUMBING"
HDL_TAP"TRUE";
"B \NAC \NWC"3;
"S \NAC"
BN"40"109;
%"TAP"
"6","(-1700,3650)","2","mstr_standard","I68";
;
CDS_LIB"mstr_standard"
BODY_TYPE"PLUMBING"
HDL_TAP"TRUE";
"B \NAC \NWC"3;
"S \NAC"
BN"38"107;
%"TAP"
"6","(-1700,3700)","2","mstr_standard","I69";
;
CDS_LIB"mstr_standard"
BODY_TYPE"PLUMBING"
HDL_TAP"TRUE";
"B \NAC \NWC"3;
"S \NAC"
BN"41"108;
%"TAP"
"6","(900,4850)","2","mstr_standard","I7";
;
CDS_LIB"mstr_standard"
BODY_TYPE"PLUMBING"
HDL_TAP"TRUE";
"B \NAC \NWC"1;
"S \NAC"
BN"14"166;
%"TAP"
"6","(-1700,3800)","2","mstr_standard","I70";
;
CDS_LIB"mstr_standard"
BODY_TYPE"PLUMBING"
HDL_TAP"TRUE";
"B \NAC \NWC"3;
"S \NAC"
BN"43"110;
%"TAP"
"6","(-1700,3850)","2","mstr_standard","I71";
;
CDS_LIB"mstr_standard"
BODY_TYPE"PLUMBING"
HDL_TAP"TRUE";
"B \NAC \NWC"3;
"S \NAC"
BN"42"111;
%"TAP"
"6","(-1700,3450)","2","mstr_standard","I72";
;
CDS_LIB"mstr_standard"
BODY_TYPE"PLUMBING"
HDL_TAP"TRUE";
"B \NAC \NWC"3;
"S \NAC"
BN"34"96;
%"TAP"
"6","(-1700,3400)","2","mstr_standard","I73";
;
CDS_LIB"mstr_standard"
BODY_TYPE"PLUMBING"
HDL_TAP"TRUE";
"B \NAC \NWC"3;
"S \NAC"
BN"35"101;
%"TAP"
"6","(-1700,3500)","2","mstr_standard","I74";
;
CDS_LIB"mstr_standard"
BODY_TYPE"PLUMBING"
HDL_TAP"TRUE";
"B \NAC \NWC"3;
"S \NAC"
BN"37"95;
%"TAP"
"6","(-1700,3550)","2","mstr_standard","I75";
;
CDS_LIB"mstr_standard"
BODY_TYPE"PLUMBING"
HDL_TAP"TRUE";
"B \NAC \NWC"3;
"S \NAC"
BN"36"102;
%"TAP"
"6","(-1700,3600)","2","mstr_standard","I76";
;
CDS_LIB"mstr_standard"
BODY_TYPE"PLUMBING"
HDL_TAP"TRUE";
"B \NAC \NWC"3;
"S \NAC"
BN"39"106;
%"TAP"
"6","(-1700,3200)","2","mstr_standard","I77";
;
CDS_LIB"mstr_standard"
BODY_TYPE"PLUMBING"
HDL_TAP"TRUE";
"B \NAC \NWC"3;
"S \NAC"
BN"31"97;
%"TAP"
"6","(-1700,3250)","2","mstr_standard","I78";
;
CDS_LIB"mstr_standard"
BODY_TYPE"PLUMBING"
HDL_TAP"TRUE";
"B \NAC \NWC"3;
"S \NAC"
BN"30"98;
%"TAP"
"6","(-1700,3150)","2","mstr_standard","I79";
;
CDS_LIB"mstr_standard"
BODY_TYPE"PLUMBING"
HDL_TAP"TRUE";
"B \NAC \NWC"3;
"S \NAC"
BN"28"104;
%"TAP"
"6","(900,4750)","2","mstr_standard","I8";
;
CDS_LIB"mstr_standard"
BODY_TYPE"PLUMBING"
HDL_TAP"TRUE";
"B \NAC \NWC"1;
"S \NAC"
BN"13"168;
%"TAP"
"6","(-1700,3300)","2","mstr_standard","I80";
;
CDS_LIB"mstr_standard"
BODY_TYPE"PLUMBING"
HDL_TAP"TRUE";
"B \NAC \NWC"3;
"S \NAC"
BN"33"99;
%"TAP"
"6","(-1700,3350)","2","mstr_standard","I81";
;
CDS_LIB"mstr_standard"
BODY_TYPE"PLUMBING"
HDL_TAP"TRUE";
"B \NAC \NWC"3;
"S \NAC"
BN"32"100;
%"TAP"
"6","(-1700,2950)","2","mstr_standard","I82";
;
CDS_LIB"mstr_standard"
BODY_TYPE"PLUMBING"
HDL_TAP"TRUE";
"B \NAC \NWC"3;
"S \NAC"
BN"24"93;
%"TAP"
"6","(-1700,2900)","2","mstr_standard","I83";
;
CDS_LIB"mstr_standard"
BODY_TYPE"PLUMBING"
HDL_TAP"TRUE";
"B \NAC \NWC"3;
"S \NAC"
BN"25"92;
%"TAP"
"6","(-1700,3000)","2","mstr_standard","I84";
;
CDS_LIB"mstr_standard"
BODY_TYPE"PLUMBING"
HDL_TAP"TRUE";
"B \NAC \NWC"3;
"S \NAC"
BN"27"85;
%"TAP"
"6","(-1700,3100)","2","mstr_standard","I85";
;
CDS_LIB"mstr_standard"
BODY_TYPE"PLUMBING"
HDL_TAP"TRUE";
"B \NAC \NWC"3;
"S \NAC"
BN"29"103;
%"TAP"
"6","(-1700,3050)","2","mstr_standard","I86";
;
CDS_LIB"mstr_standard"
BODY_TYPE"PLUMBING"
HDL_TAP"TRUE";
"B \NAC \NWC"3;
"S \NAC"
BN"26"86;
%"TAP"
"6","(-1700,2650)","2","mstr_standard","I87";
;
CDS_LIB"mstr_standard"
BODY_TYPE"PLUMBING"
HDL_TAP"TRUE";
"B \NAC \NWC"3;
"S \NAC"
BN"18"88;
%"TAP"
"6","(-1700,2700)","2","mstr_standard","I88";
;
CDS_LIB"mstr_standard"
BODY_TYPE"PLUMBING"
HDL_TAP"TRUE";
"B \NAC \NWC"3;
"S \NAC"
BN"21"89;
%"TAP"
"6","(-1700,2750)","2","mstr_standard","I89";
;
CDS_LIB"mstr_standard"
BODY_TYPE"PLUMBING"
HDL_TAP"TRUE";
"B \NAC \NWC"3;
"S \NAC"
BN"20"90;
%"TAP"
"6","(900,4650)","2","mstr_standard","I9";
;
CDS_LIB"mstr_standard"
BODY_TYPE"PLUMBING"
HDL_TAP"TRUE";
"B \NAC \NWC"1;
"S \NAC"
BN"12"170;
%"TAP"
"6","(-1700,2850)","2","mstr_standard","I90";
;
CDS_LIB"mstr_standard"
BODY_TYPE"PLUMBING"
HDL_TAP"TRUE";
"B \NAC \NWC"3;
"S \NAC"
BN"22"91;
%"TAP"
"6","(-1700,2800)","2","mstr_standard","I91";
;
CDS_LIB"mstr_standard"
BODY_TYPE"PLUMBING"
HDL_TAP"TRUE";
"B \NAC \NWC"3;
"S \NAC"
BN"23"94;
%"TAP"
"6","(-1700,2400)","2","mstr_standard","I92";
;
CDS_LIB"mstr_standard"
BODY_TYPE"PLUMBING"
HDL_TAP"TRUE";
"B \NAC \NWC"3;
"S \NAC"
BN"15"83;
%"TAP"
"6","(-1700,2450)","2","mstr_standard","I93";
;
CDS_LIB"mstr_standard"
BODY_TYPE"PLUMBING"
HDL_TAP"TRUE";
"B \NAC \NWC"3;
"S \NAC"
BN"14"75;
%"TAP"
"6","(-1700,2550)","2","mstr_standard","I94";
;
CDS_LIB"mstr_standard"
BODY_TYPE"PLUMBING"
HDL_TAP"TRUE";
"B \NAC \NWC"3;
"S \NAC"
BN"16"74;
%"TAP"
"6","(-1700,2500)","2","mstr_standard","I95";
;
CDS_LIB"mstr_standard"
BODY_TYPE"PLUMBING"
HDL_TAP"TRUE";
"B \NAC \NWC"3;
"S \NAC"
BN"17"84;
%"TAP"
"6","(-1700,2600)","2","mstr_standard","I96";
;
CDS_LIB"mstr_standard"
BODY_TYPE"PLUMBING"
HDL_TAP"TRUE";
"B \NAC \NWC"3;
"S \NAC"
BN"19"87;
%"TAP"
"6","(-1700,2350)","2","mstr_standard","I97";
;
CDS_LIB"mstr_standard"
BODY_TYPE"PLUMBING"
HDL_TAP"TRUE";
"B \NAC \NWC"3;
"S \NAC"
BN"12"82;
%"TAP"
"6","(-1700,2250)","2","mstr_standard","I98";
;
CDS_LIB"mstr_standard"
BODY_TYPE"PLUMBING"
HDL_TAP"TRUE";
"B \NAC \NWC"3;
"S \NAC"
BN"10"80;
%"TAP"
"6","(-1700,2300)","2","mstr_standard","I99";
;
CDS_LIB"mstr_standard"
BODY_TYPE"PLUMBING"
HDL_TAP"TRUE";
"B \NAC \NWC"3;
"S \NAC"
BN"13"81;
END.
